# T6G (Grand Teton) — schematic netlist excerpt (pin names and nets, part order shuffled) for the footprints in the layout excerpt that follows; sources: Cadence DE-HDL packaged netlist, KiCad conversion of 04192023_DAF0TMB3IC0_F0TG_MB_C_brd_V02_OCP.brd

U247  9FGL0251DKILFT  IC  pkg VFQFPN24_TH_0-5_4X4XI  page 233
  \xin||clkin_25\  = CLK_GEN2_XTAL_IN
  X2  = CLK_GEN2_XTAL_OUT
  \vddxtal3.3\  = VFG3P3_CLK_GEN
  \vsadr||ref3.3\  = CLK_GEN2_SMB_SADR
  GNDREF  = GND
  GNDDIG  = GND
  \vdddig3.3\  = VFG3P3_CLK_GEN
  \sclk_3.3\  = SMB_HOST_CLK_GEN2_3V3AUX_SCL
  \sdata_3.3\  = SMB_HOST_CLK_GEN2_3V3AUX_SDA
  GND_10  = GND
  \vdd3.3_11\  = VFG3P3_CLK_GEN
  \voe0#\  = CLK_GEN2_BMC_RC_OE_R3_N
  DIF0  = CLK_100M_BMC_RC_DP_R
  \dif0#\  = CLK_100M_BMC_RC_DN_R
  GNDA  = GND
  \vdda3.3\  = VFG_3P3A_CLK_GEN
  DIF1  = CLK_100M_GPU_FPGA_DP_R
  \dif1#\  = CLK_100M_GPU_FPGA_DN_R
  \voe1#\  = CLK_GEN2_GPU_OE_N
  \vdd3.3_20\  = VFG3P3_CLK_GEN
  GND_21  = GND
  \^ckpwrgd_pd#\  = P3V3_PWRGD_CLKGEN
  \^vss_en_tri\  = FG_SS_EN
  GNDXTAL  = GND
  TH_GND  = GND

(kicad_pcb
	(version 20260206)
	(generator "pcbnew")
	(generator_version "10.0")
	(general
		(thickness 1.6)
		(legacy_teardrops no)
	)
	(paper "A4")
	(title_block
		(title "04192023_DAF0TMB3IC0_F0TG_MB_C_brd_V02_OCP.brd")
		(comment 1 "Grand Teton / footprints 1168-1168 of 8354")
	)
	(layers
		(0 "F.Cu" signal "TOP")
		(4 "In1.Cu" signal "GND")
		(6 "In2.Cu" signal "IN1")
		(8 "In3.Cu" signal "GND1")
		(10 "In4.Cu" signal "IN2")
		(12 "In5.Cu" signal "GND2")
		(14 "In6.Cu" signal "IN3")
		(16 "In7.Cu" signal "GND3")
		(18 "In8.Cu" signal "VCC")
		(20 "In9.Cu" signal "VCC1")
		(22 "In10.Cu" signal "GND4")
		(24 "In11.Cu" signal "IN4")
		(26 "In12.Cu" signal "GND5")
		(28 "In13.Cu" signal "IN5")
		(30 "In14.Cu" signal "GND6")
		(32 "In15.Cu" signal "IN6")
		(34 "In16.Cu" signal "GND7")
		(2 "B.Cu" signal "BOTTOM")
		(9 "F.Adhes" user "F.Adhesive")
		(11 "B.Adhes" user "B.Adhesive")
		(13 "F.Paste" user "Package Geometry/Pastemask Top")
		(15 "B.Paste" user "Package Geometry/Pastemask Bottom")
		(5 "F.SilkS" user "Ref Des/Silkscreen Top")
		(7 "B.SilkS" user "Ref Des/Silkscreen Bottom")
		(1 "F.Mask" user "Board Geometry/Soldermask Top")
		(3 "B.Mask" user "Board Geometry/Soldermask Bottom")
		(17 "Dwgs.User" user "User.Drawings")
		(19 "Cmts.User" user "User.Comments")
		(21 "Eco1.User" user "User.Eco1")
		(23 "Eco2.User" user "User.Eco2")
		(25 "Edge.Cuts" user "Board Geometry/Outline")
		(27 "Margin" user)
		(31 "F.CrtYd" user "Package Geometry/Place Bound Top")
		(29 "B.CrtYd" user "Package Geometry/Place Bound Bottom")
		(35 "F.Fab" user "Ref Des/Assembly Top")
		(33 "B.Fab" user "Ref Des/Assembly Bottom")
	)
	(footprint ""
		(layer "F.Cu")
		(at 13.546582 -134.039102)
		(property "Reference" "U247"
			(at -2.7432 -3.012948 0)
			(unlocked yes)
			(layer "F.SilkS")
			(effects
				(font
					(size 0.7874 0.5842)
					(thickness 0.1524)
				)
				(justify left)
			)
		)
		(property "Value" ""
			(at 0 0 0)
			(layer "F.Fab")
			(effects
				(font
					(size 1.27 1.27)
				)
			)
		)
		(duplicate_pad_numbers_are_jumpers no)
		(fp_line
			(start -2.050034 -2.050034)
			(end -2.050034 -1.516634)
			(stroke
				(width 0.1524)
				(type default)
			)
			(layer "F.SilkS")
		)
		(fp_line
			(start -2.050034 1.516634)
			(end -2.050034 2.050034)
			(stroke
				(width 0.1524)
				(type default)
			)
			(layer "F.SilkS")
		)
		(fp_line
			(start -2.050034 2.050034)
			(end -1.516634 2.050034)
			(stroke
				(width 0.1524)
				(type default)
			)
			(layer "F.SilkS")
		)
		(fp_line
			(start -1.516634 -2.050034)
			(end -2.050034 -2.050034)
			(stroke
				(width 0.1524)
				(type default)
			)
			(layer "F.SilkS")
		)
		(fp_line
			(start 1.516634 2.050034)
			(end 2.050034 2.050034)
			(stroke
				(width 0.1524)
				(type default)
			)
			(layer "F.SilkS")
		)
		(fp_line
			(start 2.050034 -2.050034)
			(end 1.516634 -2.050034)
			(stroke
				(width 0.1524)
				(type default)
			)
			(layer "F.SilkS")
		)
		(fp_line
			(start 2.050034 -1.516634)
			(end 2.050034 -2.050034)
			(stroke
				(width 0.1524)
				(type default)
			)
			(layer "F.SilkS")
		)
		(fp_line
			(start 2.050034 2.050034)
			(end 2.050034 1.516634)
			(stroke
				(width 0.1524)
				(type default)
			)
			(layer "F.SilkS")
		)
		(fp_poly
			(pts
				(xy -2.634234 -1.542034) (xy -2.050034 -1.542034) (xy -2.050034 -2.126234) (xy -2.634234 -2.126234)
			)
			(stroke
				(width 0)
				(type default)
			)
			(fill yes)
			(layer "F.SilkS")
		)
		(fp_line
			(start -2.050034 -2.050034)
			(end -2.050034 2.050034)
			(stroke
				(width 0.1)
				(type default)
			)
			(layer "F.Fab")
		)
		(fp_line
			(start -2.050034 2.050034)
			(end 2.050034 2.050034)
			(stroke
				(width 0.1)
				(type default)
			)
			(layer "F.Fab")
		)
		(fp_line
			(start 2.050034 -2.050034)
			(end -2.050034 -2.050034)
			(stroke
				(width 0.1)
				(type default)
			)
			(layer "F.Fab")
		)
		(fp_line
			(start 2.050034 2.050034)
			(end 2.050034 -2.050034)
			(stroke
				(width 0.1)
				(type default)
			)
			(layer "F.Fab")
		)
		(fp_poly
			(pts
				(xy -2.634234 -1.542034) (xy -2.050034 -1.542034) (xy -2.050034 -2.126234) (xy -2.634234 -2.126234)
			)
			(stroke
				(width 0)
				(type default)
			)
			(fill yes)
			(layer "F.Fab")
		)
		(pad "1" smd rect
			(at -1.875028 -1.249934 270)
			(size 0.254 0.5588)
			(layers "F.Cu" "F.Mask" "F.Paste")
			(net "CLK_GEN2_XTAL_IN")
		)
		(pad "2" smd rect
			(at -1.875028 -0.750062 270)
			(size 0.254 0.5588)
			(layers "F.Cu" "F.Mask" "F.Paste")
			(net "CLK_GEN2_XTAL_OUT")
		)
		(pad "3" smd rect
			(at -1.875028 -0.249936 270)
			(size 0.254 0.5588)
			(layers "F.Cu" "F.Mask" "F.Paste")
			(net "VFG3P3_CLK_GEN")
		)
		(pad "4" smd rect
			(at -1.875028 0.249936 270)
			(size 0.254 0.5588)
			(layers "F.Cu" "F.Mask" "F.Paste")
			(net "CLK_GEN2_SMB_SADR")
		)
		(pad "5" smd rect
			(at -1.875028 0.750062 270)
			(size 0.254 0.5588)
			(layers "F.Cu" "F.Mask" "F.Paste")
			(net "GND")
		)
		(pad "6" smd rect
			(at -1.875028 1.249934 270)
			(size 0.254 0.5588)
			(layers "F.Cu" "F.Mask" "F.Paste")
			(net "GND")
		)
		(pad "7" smd rect
			(at -1.249934 1.875028)
			(size 0.254 0.5588)
			(layers "F.Cu" "F.Mask" "F.Paste")
			(net "VFG3P3_CLK_GEN")
		)
		(pad "8" smd rect
			(at -0.750062 1.875028)
			(size 0.254 0.5588)
			(layers "F.Cu" "F.Mask" "F.Paste")
			(net "SMB_HOST_CLK_GEN2_3V3AUX_SCL")
		)
		(pad "9" smd rect
			(at -0.249936 1.875028)
			(size 0.254 0.5588)
			(layers "F.Cu" "F.Mask" "F.Paste")
			(net "SMB_HOST_CLK_GEN2_3V3AUX_SDA")
		)
		(pad "10" smd rect
			(at 0.249936 1.875028)
			(size 0.254 0.5588)
			(layers "F.Cu" "F.Mask" "F.Paste")
			(net "GND")
		)
		(pad "11" smd rect
			(at 0.750062 1.875028)
			(size 0.254 0.5588)
			(layers "F.Cu" "F.Mask" "F.Paste")
			(net "VFG3P3_CLK_GEN")
		)
		(pad "12" smd rect
			(at 1.249934 1.875028)
			(size 0.254 0.5588)
			(layers "F.Cu" "F.Mask" "F.Paste")
			(net "CLK_GEN2_BMC_RC_OE_R3_N")
		)
		(pad "13" smd rect
			(at 1.875028 1.249934 270)
			(size 0.254 0.5588)
			(layers "F.Cu" "F.Mask" "F.Paste")
			(net "CLK_100M_BMC_RC_DP_R")
		)
		(pad "14" smd rect
			(at 1.875028 0.750062 270)
			(size 0.254 0.5588)
			(layers "F.Cu" "F.Mask" "F.Paste")
			(net "CLK_100M_BMC_RC_DN_R")
		)
		(pad "15" smd rect
			(at 1.875028 0.249936 270)
			(size 0.254 0.5588)
			(layers "F.Cu" "F.Mask" "F.Paste")
			(net "GND")
		)
		(pad "16" smd rect
			(at 1.875028 -0.249936 270)
			(size 0.254 0.5588)
			(layers "F.Cu" "F.Mask" "F.Paste")
			(net "VFG_3P3A_CLK_GEN")
		)
		(pad "17" smd rect
			(at 1.875028 -0.750062 270)
			(size 0.254 0.5588)
			(layers "F.Cu" "F.Mask" "F.Paste")
			(net "CLK_100M_GPU_FPGA_DP_R")
		)
		(pad "18" smd rect
			(at 1.875028 -1.249934 270)
			(size 0.254 0.5588)
			(layers "F.Cu" "F.Mask" "F.Paste")
			(net "CLK_100M_GPU_FPGA_DN_R")
		)
		(pad "19" smd rect
			(at 1.249934 -1.875028)
			(size 0.254 0.5588)
			(layers "F.Cu" "F.Mask" "F.Paste")
			(net "CLK_GEN2_GPU_OE_N")
		)
		(pad "20" smd rect
			(at 0.750062 -1.875028)
			(size 0.254 0.5588)
			(layers "F.Cu" "F.Mask" "F.Paste")
			(net "VFG3P3_CLK_GEN")
		)
		(pad "21" smd rect
			(at 0.249936 -1.875028)
			(size 0.254 0.5588)
			(layers "F.Cu" "F.Mask" "F.Paste")
			(net "GND")
		)
		(pad "22" smd rect
			(at -0.249936 -1.875028)
			(size 0.254 0.5588)
			(layers "F.Cu" "F.Mask" "F.Paste")
			(net "P3V3_PWRGD_CLKGEN")
		)
		(pad "23" smd rect
			(at -0.750062 -1.875028)
			(size 0.254 0.5588)
			(layers "F.Cu" "F.Mask" "F.Paste")
			(net "FG_SS_EN")
		)
		(pad "24" smd rect
			(at -1.249934 -1.875028)
			(size 0.254 0.5588)
			(layers "F.Cu" "F.Mask" "F.Paste")
			(net "GND")
		)
		(pad "25" smd circle
			(at 0 0)
			(size 0 0)
			(layers "F.Cu" "F.Mask" "F.Paste")
			(net "GND")
		)
	)
)
